(kicad_pcb
	(version 20260206)
	(generator "pcbnew")
	(generator_version "10.0")
	(general
		(thickness 1.6)
		(legacy_teardrops no)
	)
	(paper "A4")
	(title_block
		(title "01162023_DA0F0TEBIF0_F0T_Expander_BD_F_brd_V02_OCP.brd")
		(comment 1 "Grand Teton / footprints 4905-4910 of 9728")
	)
	(layers
		(0 "F.Cu" signal "TOP")
		(4 "In1.Cu" signal "GND")
		(6 "In2.Cu" signal "VCC")
		(8 "In3.Cu" signal "VCC1")
		(10 "In4.Cu" signal "GND1")
		(12 "In5.Cu" signal "IN1")
		(14 "In6.Cu" signal "GND2")
		(16 "In7.Cu" signal "IN2")
		(18 "In8.Cu" signal "GND3")
		(20 "In9.Cu" signal "IN3")
		(22 "In10.Cu" signal "GND4")
		(24 "In11.Cu" signal "IN4")
		(26 "In12.Cu" signal "GND5")
		(28 "In13.Cu" signal "IN5")
		(30 "In14.Cu" signal "GND6")
		(32 "In15.Cu" signal "IN6")
		(34 "In16.Cu" signal "GND7")
		(2 "B.Cu" signal "BOTTOM")
		(9 "F.Adhes" user "F.Adhesive")
		(11 "B.Adhes" user "B.Adhesive")
		(13 "F.Paste" user "Package Geometry/Pastemask Top")
		(15 "B.Paste" user "Package Geometry/Pastemask Bottom")
		(5 "F.SilkS" user "Ref Des/Silkscreen Top")
		(7 "B.SilkS" user "Ref Des/Silkscreen Bottom")
		(1 "F.Mask" user "Board Geometry/Soldermask Top")
		(3 "B.Mask" user "Board Geometry/Soldermask Bottom")
		(17 "Dwgs.User" user "User.Drawings")
		(19 "Cmts.User" user "User.Comments")
		(21 "Eco1.User" user "User.Eco1")
		(23 "Eco2.User" user "User.Eco2")
		(25 "Edge.Cuts" user "Board Geometry/Outline")
		(27 "Margin" user)
		(31 "F.CrtYd" user "Package Geometry/Place Bound Top")
		(29 "B.CrtYd" user "Package Geometry/Place Bound Bottom")
		(35 "F.Fab" user "Ref Des/Assembly Top")
		(33 "B.Fab" user "Ref Des/Assembly Bottom")
	)
	(footprint ""
		(layer "F.Cu")
		(at 105.971594 -284.8991 180)
		(property "Reference" "PU7"
			(at -30.236922 -1.54813 90)
			(unlocked yes)
			(layer "F.SilkS")
			(effects
				(font
					(size 0.7874 0.5842)
					(thickness 0.1524)
				)
			)
		)
		(property "Value" ""
			(at 0 0 180)
			(layer "F.Fab")
			(effects
				(font
					(size 1.27 1.27)
				)
			)
		)
		(duplicate_pad_numbers_are_jumpers no)
		(fp_line
			(start 2.500122 2.999994)
			(end 2.2987 2.999994)
			(stroke
				(width 0.1524)
				(type default)
			)
			(layer "F.SilkS")
		)
		(fp_line
			(start 2.500122 2.339594)
			(end 2.500122 2.999994)
			(stroke
				(width 0.1524)
				(type default)
			)
			(layer "F.SilkS")
		)
		(fp_line
			(start 2.500122 -2.999994)
			(end 2.500122 -2.44348)
			(stroke
				(width 0.1524)
				(type default)
			)
			(layer "F.SilkS")
		)
		(fp_line
			(start 2.31394 -2.999994)
			(end 2.500122 -2.999994)
			(stroke
				(width 0.1524)
				(type default)
			)
			(layer "F.SilkS")
		)
		(fp_line
			(start -2.2987 2.999994)
			(end -2.500122 2.999994)
			(stroke
				(width 0.1524)
				(type default)
			)
			(layer "F.SilkS")
		)
		(fp_line
			(start -2.500122 2.999994)
			(end -2.500122 2.339594)
			(stroke
				(width 0.1524)
				(type default)
			)
			(layer "F.SilkS")
		)
		(fp_line
			(start -2.500122 0.6604)
			(end -2.500122 0.229108)
			(stroke
				(width 0.1524)
				(type default)
			)
			(layer "F.SilkS")
		)
		(fp_line
			(start -2.500122 -2.529078)
			(end -2.500122 -2.999994)
			(stroke
				(width 0.1524)
				(type default)
			)
			(layer "F.SilkS")
		)
		(fp_line
			(start -2.500122 -2.999994)
			(end -2.24409 -2.999994)
			(stroke
				(width 0.1524)
				(type default)
			)
			(layer "F.SilkS")
		)
		(fp_poly
			(pts
				(xy -2.118106 -4.109466) (xy -3.134106 -4.109466) (xy -2.626106 -3.093466)
			)
			(stroke
				(width 0)
				(type default)
			)
			(fill yes)
			(layer "F.SilkS")
		)
		(fp_line
			(start 2.500122 2.999994)
			(end -2.500122 2.999994)
			(stroke
				(width 0.1)
				(type default)
			)
			(layer "F.Fab")
		)
		(fp_line
			(start 2.500122 -2.999994)
			(end 2.500122 2.999994)
			(stroke
				(width 0.1)
				(type default)
			)
			(layer "F.Fab")
		)
		(fp_line
			(start -2.500122 2.999994)
			(end -2.500122 -2.999994)
			(stroke
				(width 0.1)
				(type default)
			)
			(layer "F.Fab")
		)
		(fp_line
			(start -2.500122 -2.999994)
			(end 2.500122 -2.999994)
			(stroke
				(width 0.1)
				(type default)
			)
			(layer "F.Fab")
		)
		(fp_poly
			(pts
				(xy -4.218432 -2.783078) (xy -4.218432 -1.767078) (xy -3.202432 -2.275078)
			)
			(stroke
				(width 0)
				(type default)
			)
			(fill yes)
			(layer "F.Fab")
		)
		(pad "1" smd rect
			(at -2.400046 -2.275078 270)
			(size 0.2286 0.6096)
			(layers "F.Cu" "F.Mask" "F.Paste")
			(net "SW_P0V8_PEX0_VOS1")
		)
		(pad "2" smd rect
			(at -2.400046 -1.82499 270)
			(size 0.2286 0.6096)
			(layers "F.Cu" "F.Mask" "F.Paste")
			(net "GND")
		)
		(pad "3" smd rect
			(at -2.400046 -1.374902 270)
			(size 0.2286 0.6096)
			(layers "F.Cu" "F.Mask" "F.Paste")
			(net "P0V8_PEX0_VCC1")
		)
		(pad "4" smd rect
			(at -2.400046 -0.925068 270)
			(size 0.2286 0.6096)
			(layers "F.Cu" "F.Mask" "F.Paste")
			(net "P0V8_PEX0_PVCC")
		)
		(pad "5" smd rect
			(at -2.400046 -0.47498 270)
			(size 0.2286 0.6096)
			(layers "F.Cu" "F.Mask" "F.Paste")
			(net "GND")
		)
		(pad "6" smd rect
			(at -2.400046 -0.024892 270)
			(size 0.2286 0.6096)
			(layers "F.Cu" "F.Mask" "F.Paste")
			(net "NC_P0V8_PEX0_PH1_NC1")
		)
		(pad "7_9-20_24" smd circle
			(at 0 1.150112 270)
			(size 0 0)
			(layers "F.Cu" "F.Mask" "F.Paste")
			(net "GND")
		)
		(pad "10_19" smd rect
			(at 0 2.899918 270)
			(size 0.6096 4.318)
			(layers "F.Cu" "F.Mask" "F.Paste")
			(net "SW_P0V8_PEX0_PH1")
		)
		(pad "25_29" smd rect
			(at 1.549908 -1.279906 90)
			(size 2.0574 2.3114)
			(layers "F.Cu" "F.Mask" "F.Paste")
			(net "SW_P12V_P0V8_PEX0_FLT")
		)
		(pad "30" smd rect
			(at 2.05994 -2.899918 180)
			(size 0.2286 0.6096)
			(layers "F.Cu" "F.Mask" "F.Paste")
			(net "SW_P12V_P0V8_PEX0_FLT")
		)
		(pad "31" smd rect
			(at 1.610106 -2.899918 180)
			(size 0.2286 0.6096)
			(layers "F.Cu" "F.Mask" "F.Paste")
			(net "NC_P0V8_PEX0_PH1_NC3")
		)
		(pad "32" smd rect
			(at 1.160018 -2.899918 180)
			(size 0.2286 0.6096)
			(layers "F.Cu" "F.Mask" "F.Paste")
			(net "SW_P0V8_PEX0_PHASE1")
		)
		(pad "33" smd rect
			(at 0.70993 -2.899918 180)
			(size 0.2286 0.6096)
			(layers "F.Cu" "F.Mask" "F.Paste")
			(net "SW_P0V8_PEX0_BOOT1")
		)
		(pad "34" smd rect
			(at 0.260096 -2.899918 180)
			(size 0.2286 0.6096)
			(layers "F.Cu" "F.Mask" "F.Paste")
			(net "P0V8_PEX0_PWM1")
		)
		(pad "35" smd rect
			(at -0.189992 -2.899918 180)
			(size 0.2286 0.6096)
			(layers "F.Cu" "F.Mask" "F.Paste")
			(net "P0V8_PEX0_EN1")
		)
		(pad "36" smd rect
			(at -0.64008 -2.899918 180)
			(size 0.2286 0.6096)
			(layers "F.Cu" "F.Mask" "F.Paste")
			(net "P0V8_PEX0_TSEN")
		)
		(pad "37" smd rect
			(at -1.089914 -2.899918 180)
			(size 0.2286 0.6096)
			(layers "F.Cu" "F.Mask" "F.Paste")
			(net "P0V8_PEX0_LSET1")
		)
		(pad "38" smd rect
			(at -1.540002 -2.899918 180)
			(size 0.2286 0.6096)
			(layers "F.Cu" "F.Mask" "F.Paste")
			(net "P0V8_PEX0_ISEN1")
		)
		(pad "39" smd rect
			(at -1.99009 -2.899918 180)
			(size 0.2286 0.6096)
			(layers "F.Cu" "F.Mask" "F.Paste")
			(net "P0V8_PEX0_VREF")
		)
		(pad "40" smd rect
			(at -0.87503 -1.27508 180)
			(size 1.7526 1.9558)
			(layers "F.Cu" "F.Mask" "F.Paste")
			(net "GND")
		)
		(pad "41" smd rect
			(at -1.525016 0.249936 90)
			(size 0.3048 0.4572)
			(layers "F.Cu" "F.Mask" "F.Paste")
			(net "NC_P0V8_PEX0_PH1_NC2")
		)
		(zone
			(layer "F.Cu")
			(hatch none 0.5)
			(connect_pads
				(clearance 0)
			)
			(min_thickness 0.25)
			(keepout
				(tracks not_allowed)
				(vias allowed)
				(pads allowed)
				(copperpour not_allowed)
				(footprints allowed)
			)
			(placement
				(enabled no)
				(sheetname "")
			)
			(fill
				(thermal_gap 0.5)
				(thermal_bridge_width 0.5)
				(island_removal_mode 0)
			)
			(polygon
				(pts
					(xy 108.471716 -287.899094) (xy 108.471716 -287.149794) (xy 103.471472 -287.149794) (xy 103.471472 -287.899094)
					(xy 103.761794 -287.899094) (xy 103.761794 -287.443418) (xy 108.181394 -287.443418) (xy 108.181394 -287.899094)
				)
			)
		)
	)
	(footprint ""
		(layer "F.Cu")
		(at 387.580632 -135.815324)
		(property "Reference" "C666"
			(at 0 0 0)
			(layer "F.SilkS")
			(hide yes)
			(effects
				(font
					(size 1.27 1.27)
				)
			)
		)
		(property "Value" ""
			(at 0 0 0)
			(layer "F.Fab")
			(effects
				(font
					(size 1.27 1.27)
				)
			)
		)
		(duplicate_pad_numbers_are_jumpers no)
		(fp_line
			(start -0.299974 -0.150114)
			(end 0.299974 -0.150114)
			(stroke
				(width 0.1)
				(type default)
			)
			(layer "F.Fab")
		)
		(fp_line
			(start -0.299974 0.150114)
			(end -0.299974 -0.150114)
			(stroke
				(width 0.1)
				(type default)
			)
			(layer "F.Fab")
		)
		(fp_line
			(start 0.299974 -0.150114)
			(end 0.299974 0.150114)
			(stroke
				(width 0.1)
				(type default)
			)
			(layer "F.Fab")
		)
		(fp_line
			(start 0.299974 0.150114)
			(end -0.299974 0.150114)
			(stroke
				(width 0.1)
				(type default)
			)
			(layer "F.Fab")
		)
		(pad "1" smd rect
			(at -0.2667 0)
			(size 0.3048 0.381)
			(layers "F.Cu" "F.Mask" "F.Paste")
			(net "P5E_PEX3_STN1_TX_DN<31>")
		)
		(pad "2" smd rect
			(at 0.2667 0)
			(size 0.3048 0.381)
			(layers "F.Cu" "F.Mask" "F.Paste")
			(net "P5E_PEX3_STN1_TX_C_DN<31>")
		)
	)
	(footprint ""
		(layer "F.Cu")
		(at 39.280592 -100.203254)
		(property "Reference" "C64"
			(at 0 0 0)
			(layer "F.SilkS")
			(hide yes)
			(effects
				(font
					(size 1.27 1.27)
				)
			)
		)
		(property "Value" ""
			(at 0 0 0)
			(layer "F.Fab")
			(effects
				(font
					(size 1.27 1.27)
				)
			)
		)
		(duplicate_pad_numbers_are_jumpers no)
		(fp_line
			(start -0.299974 -0.150114)
			(end 0.299974 -0.150114)
			(stroke
				(width 0.1)
				(type default)
			)
			(layer "F.Fab")
		)
		(fp_line
			(start -0.299974 0.150114)
			(end -0.299974 -0.150114)
			(stroke
				(width 0.1)
				(type default)
			)
			(layer "F.Fab")
		)
		(fp_line
			(start 0.299974 -0.150114)
			(end 0.299974 0.150114)
			(stroke
				(width 0.1)
				(type default)
			)
			(layer "F.Fab")
		)
		(fp_line
			(start 0.299974 0.150114)
			(end -0.299974 0.150114)
			(stroke
				(width 0.1)
				(type default)
			)
			(layer "F.Fab")
		)
		(pad "1" smd rect
			(at -0.2667 0)
			(size 0.3048 0.381)
			(layers "F.Cu" "F.Mask" "F.Paste")
			(net "P5E_PEX0_STN1_TX_DN<16>")
		)
		(pad "2" smd rect
			(at 0.2667 0)
			(size 0.3048 0.381)
			(layers "F.Cu" "F.Mask" "F.Paste")
			(net "P5E_PEX0_STN1_TX_C_DN<16>")
		)
	)
	(footprint ""
		(layer "F.Cu")
		(at 408.559 -383.667 90)
		(property "Reference" "R6272"
			(at 0 0 90)
			(layer "F.SilkS")
			(hide yes)
			(effects
				(font
					(size 1.27 1.27)
				)
			)
		)
		(property "Value" ""
			(at 0 0 90)
			(layer "F.Fab")
			(effects
				(font
					(size 1.27 1.27)
				)
			)
		)
		(duplicate_pad_numbers_are_jumpers no)
		(fp_line
			(start 0.7874 -0.4064)
			(end 0.7874 0.4064)
			(stroke
				(width 0.1524)
				(type default)
			)
			(layer "F.SilkS")
		)
		(fp_line
			(start -0.7874 -0.4064)
			(end 0.7874 -0.4064)
			(stroke
				(width 0.1524)
				(type default)
			)
			(layer "F.SilkS")
		)
		(fp_line
			(start 0.7874 0.4064)
			(end -0.7874 0.4064)
			(stroke
				(width 0.1524)
				(type default)
			)
			(layer "F.SilkS")
		)
		(fp_line
			(start -0.7874 0.4064)
			(end -0.7874 -0.4064)
			(stroke
				(width 0.1524)
				(type default)
			)
			(layer "F.SilkS")
		)
		(fp_line
			(start -0.12065 -0.305054)
			(end -0.12065 -0.2794)
			(stroke
				(width 0.1)
				(type default)
			)
			(layer "F.Fab")
		)
		(fp_line
			(start -0.67945 -0.305054)
			(end -0.12065 -0.305054)
			(stroke
				(width 0.1)
				(type default)
			)
			(layer "F.Fab")
		)
		(fp_line
			(start 0.67945 -0.3048)
			(end 0.67945 0.3048)
			(stroke
				(width 0.1)
				(type default)
			)
			(layer "F.Fab")
		)
		(fp_line
			(start 0.12065 -0.3048)
			(end 0.67945 -0.3048)
			(stroke
				(width 0.1)
				(type default)
			)
			(layer "F.Fab")
		)
		(fp_line
			(start 0.12065 -0.2794)
			(end 0.12065 -0.3048)
			(stroke
				(width 0.1)
				(type default)
			)
			(layer "F.Fab")
		)
		(fp_line
			(start -0.12065 -0.2794)
			(end 0.12065 -0.2794)
			(stroke
				(width 0.1)
				(type default)
			)
			(layer "F.Fab")
		)
		(fp_line
			(start 0.120396 0.2794)
			(end -0.12065 0.2794)
			(stroke
				(width 0.1)
				(type default)
			)
			(layer "F.Fab")
		)
		(fp_line
			(start -0.12065 0.2794)
			(end -0.12065 0.3048)
			(stroke
				(width 0.1)
				(type default)
			)
			(layer "F.Fab")
		)
		(fp_line
			(start 0.67945 0.3048)
			(end 0.120396 0.3048)
			(stroke
				(width 0.1)
				(type default)
			)
			(layer "F.Fab")
		)
		(fp_line
			(start 0.120396 0.3048)
			(end 0.120396 0.2794)
			(stroke
				(width 0.1)
				(type default)
			)
			(layer "F.Fab")
		)
		(fp_line
			(start -0.12065 0.3048)
			(end -0.67945 0.3048)
			(stroke
				(width 0.1)
				(type default)
			)
			(layer "F.Fab")
		)
		(fp_line
			(start -0.67945 0.3048)
			(end -0.67945 -0.305054)
			(stroke
				(width 0.1)
				(type default)
			)
			(layer "F.Fab")
		)
		(pad "1" smd circle
			(at -0.40005 0 90)
			(size 0 0)
			(layers "F.Cu" "F.Mask" "F.Paste")
			(net "MB_I3C_ISO_EN")
		)
		(pad "2" smd circle
			(at 0.40005 0 90)
			(size 0 0)
			(layers "F.Cu" "F.Mask" "F.Paste")
			(net "P3V3_AUX")
		)
	)
	(footprint ""
		(layer "F.Cu")
		(at 313.391804 -343.952322 90)
		(property "Reference" "C552"
			(at 0 0 90)
			(layer "F.SilkS")
			(hide yes)
			(effects
				(font
					(size 1.27 1.27)
				)
			)
		)
		(property "Value" ""
			(at 0 0 90)
			(layer "F.Fab")
			(effects
				(font
					(size 1.27 1.27)
				)
			)
		)
		(duplicate_pad_numbers_are_jumpers no)
		(fp_line
			(start 0.299974 -0.150114)
			(end 0.299974 0.150114)
			(stroke
				(width 0.1)
				(type default)
			)
			(layer "F.Fab")
		)
		(fp_line
			(start -0.299974 -0.150114)
			(end 0.299974 -0.150114)
			(stroke
				(width 0.1)
				(type default)
			)
			(layer "F.Fab")
		)
		(fp_line
			(start 0.299974 0.150114)
			(end -0.299974 0.150114)
			(stroke
				(width 0.1)
				(type default)
			)
			(layer "F.Fab")
		)
		(fp_line
			(start -0.299974 0.150114)
			(end -0.299974 -0.150114)
			(stroke
				(width 0.1)
				(type default)
			)
			(layer "F.Fab")
		)
		(pad "1" smd rect
			(at -0.2667 0 90)
			(size 0.3048 0.381)
			(layers "F.Cu" "F.Mask" "F.Paste")
			(net "P5E_PEX2_STN6_TX_DN<111>")
		)
		(pad "2" smd rect
			(at 0.2667 0 90)
			(size 0.3048 0.381)
			(layers "F.Cu" "F.Mask" "F.Paste")
			(net "P5E_PEX2_STN6_TX_C_DN<111>")
		)
	)
	(footprint ""
		(layer "F.Cu")
		(at 305.482752 -80.739742)
		(property "Reference" "R305"
			(at 0 0 0)
			(layer "F.SilkS")
			(hide yes)
			(effects
				(font
					(size 1.27 1.27)
				)
			)
		)
		(property "Value" ""
			(at 0 0 0)
			(layer "F.Fab")
			(effects
				(font
					(size 1.27 1.27)
				)
			)
		)
		(duplicate_pad_numbers_are_jumpers no)
		(fp_line
			(start -0.7874 -0.4064)
			(end 0.7874 -0.4064)
			(stroke
				(width 0.1524)
				(type default)
			)
			(layer "F.SilkS")
		)
		(fp_line
			(start -0.7874 0.4064)
			(end -0.7874 -0.4064)
			(stroke
				(width 0.1524)
				(type default)
			)
			(layer "F.SilkS")
		)
		(fp_line
			(start 0.7874 -0.4064)
			(end 0.7874 0.4064)
			(stroke
				(width 0.1524)
				(type default)
			)
			(layer "F.SilkS")
		)
		(fp_line
			(start 0.7874 0.4064)
			(end -0.7874 0.4064)
			(stroke
				(width 0.1524)
				(type default)
			)
			(layer "F.SilkS")
		)
		(fp_line
			(start -0.67945 -0.305054)
			(end -0.12065 -0.305054)
			(stroke
				(width 0.1)
				(type default)
			)
			(layer "F.Fab")
		)
		(fp_line
			(start -0.67945 0.3048)
			(end -0.67945 -0.305054)
			(stroke
				(width 0.1)
				(type default)
			)
			(layer "F.Fab")
		)
		(fp_line
			(start -0.12065 -0.305054)
			(end -0.12065 -0.2794)
			(stroke
				(width 0.1)
				(type default)
			)
			(layer "F.Fab")
		)
		(fp_line
			(start -0.12065 -0.2794)
			(end 0.12065 -0.2794)
			(stroke
				(width 0.1)
				(type default)
			)
			(layer "F.Fab")
		)
		(fp_line
			(start -0.12065 0.2794)
			(end -0.12065 0.3048)
			(stroke
				(width 0.1)
				(type default)
			)
			(layer "F.Fab")
		)
		(fp_line
			(start -0.12065 0.3048)
			(end -0.67945 0.3048)
			(stroke
				(width 0.1)
				(type default)
			)
			(layer "F.Fab")
		)
		(fp_line
			(start 0.120396 0.2794)
			(end -0.12065 0.2794)
			(stroke
				(width 0.1)
				(type default)
			)
			(layer "F.Fab")
		)
		(fp_line
			(start 0.120396 0.3048)
			(end 0.120396 0.2794)
			(stroke
				(width 0.1)
				(type default)
			)
			(layer "F.Fab")
		)
		(fp_line
			(start 0.12065 -0.3048)
			(end 0.67945 -0.3048)
			(stroke
				(width 0.1)
				(type default)
			)
			(layer "F.Fab")
		)
		(fp_line
			(start 0.12065 -0.2794)
			(end 0.12065 -0.3048)
			(stroke
				(width 0.1)
				(type default)
			)
			(layer "F.Fab")
		)
		(fp_line
			(start 0.67945 -0.3048)
			(end 0.67945 0.3048)
			(stroke
				(width 0.1)
				(type default)
			)
			(layer "F.Fab")
		)
		(fp_line
			(start 0.67945 0.3048)
			(end 0.120396 0.3048)
			(stroke
				(width 0.1)
				(type default)
			)
			(layer "F.Fab")
		)
		(pad "1" smd circle
			(at -0.40005 0)
			(size 0 0)
			(layers "F.Cu" "F.Mask" "F.Paste")
			(net "P3V3_AUX")
		)
		(pad "2" smd circle
			(at 0.40005 0)
			(size 0 0)
			(layers "F.Cu" "F.Mask" "F.Paste")
			(net "HP_NIC5_HSC_PWRGD_N")
		)
	)
)
